(kicad_pcb
	(version 20260206)
	(generator "pcbnew")
	(generator_version "10.0")
	(general
		(thickness 1.6)
		(legacy_teardrops no)
	)
	(paper "A4")
	(title_block
		(title "Bryce Canyon_F.DPB_16315-1-OCP.brd")
		(comment 1 "Bryce Canyon / footprints 1973-1980 of 2223")
	)
	(layers
		(0 "F.Cu" signal "TOP")
		(4 "In1.Cu" signal "L2GND")
		(6 "In2.Cu" signal "L3")
		(8 "In3.Cu" signal "L4GND")
		(10 "In4.Cu" signal "L5")
		(12 "In5.Cu" signal "L6VCC")
		(14 "In6.Cu" signal "L7VCC")
		(16 "In7.Cu" signal "L8")
		(18 "In8.Cu" signal "L9GND")
		(20 "In9.Cu" signal "L10")
		(22 "In10.Cu" signal "L11GND")
		(2 "B.Cu" signal "BOTTOM")
		(9 "F.Adhes" user "F.Adhesive")
		(11 "B.Adhes" user "B.Adhesive")
		(13 "F.Paste" user "Package Geometry/Pastemask Top")
		(15 "B.Paste" user "Package Geometry/Pastemask Bottom")
		(5 "F.SilkS" user "Ref Des/Silkscreen Top")
		(7 "B.SilkS" user "Ref Des/Silkscreen Bottom")
		(1 "F.Mask" user "Board Geometry/Soldermask Top")
		(3 "B.Mask" user "Board Geometry/Soldermask Bottom")
		(17 "Dwgs.User" user "User.Drawings")
		(19 "Cmts.User" user "User.Comments")
		(21 "Eco1.User" user "User.Eco1")
		(23 "Eco2.User" user "User.Eco2")
		(25 "Edge.Cuts" user "Board Geometry/Outline")
		(27 "Margin" user)
		(31 "F.CrtYd" user "Package Geometry/Place Bound Top")
		(29 "B.CrtYd" user "Package Geometry/Place Bound Bottom")
		(35 "F.Fab" user "Ref Des/Assembly Top")
		(33 "B.Fab" user "Ref Des/Assembly Bottom")
	)
	(footprint ""
		(layer "F.Cu")
		(at 271.759172 -238.924846 180)
		(property "Reference" "R443"
			(at 0 0 180)
			(layer "F.SilkS")
			(hide yes)
			(effects
				(font
					(size 1.27 1.27)
				)
			)
		)
		(property "Value" "1KR2F-3-GP"
			(at 0.064008 -3.993896 180)
			(unlocked yes)
			(layer "F.Fab")
			(hide yes)
			(effects
				(font
					(size 1.016 1.016)
					(thickness 0.1524)
				)
			)
		)
		(property "Device Type" "R402H16"
			(at 0.064008 -5.517896 180)
			(unlocked yes)
			(layer "F.Fab")
			(hide yes)
			(effects
				(font
					(size 1.016 1.016)
					(thickness 0.1524)
				)
			)
		)
		(duplicate_pad_numbers_are_jumpers no)
		(fp_line
			(start 0.508 -0.9398)
			(end -0.508 -0.9398)
			(stroke
				(width 0.1524)
				(type default)
			)
			(layer "F.SilkS")
		)
		(fp_line
			(start -0.508 -0.9398)
			(end -0.508 0.9398)
			(stroke
				(width 0.1524)
				(type default)
			)
			(layer "F.SilkS")
		)
		(fp_rect
			(start -0.508 0.9398)
			(end 0.508 -0.9398)
			(stroke
				(width 0)
				(type default)
			)
			(fill no)
			(layer "F.CrtYd")
		)
		(fp_rect
			(start -0.508 0.9398)
			(end 0.508 -0.9398)
			(stroke
				(width 0)
				(type default)
			)
			(fill no)
			(layer "F.Fab")
		)
		(pad "1" smd custom
			(at 0 -0.4445 180)
			(size 0.1397 0.1397)
			(layers "F.Cu" "F.Mask" "F.Paste")
			(net "P3V3_STBY_A")
			(options
				(clearance outline)
				(anchor circle)
			)
			(primitives
				(gr_poly
					(pts
						(arc
							(start -0.1778 -0.2794)
							(mid -0.249642 -0.249642)
							(end -0.2794 -0.1778)
						)
						(arc
							(start -0.2794 0.1778)
							(mid -0.249642 0.249642)
							(end -0.1778 0.2794)
						)
						(arc
							(start 0.1778 0.2794)
							(mid 0.249642 0.249642)
							(end 0.2794 0.1778)
						)
						(arc
							(start 0.2794 -0.1778)
							(mid 0.249642 -0.249642)
							(end 0.1778 -0.2794)
						)
					)
					(width 0)
					(fill yes)
				)
			)
		)
		(pad "2" smd custom
			(at 0 0.4445 180)
			(size 0.1397 0.1397)
			(layers "F.Cu" "F.Mask" "F.Paste")
			(net "I2C_BMC_A_EXP_A_SCL")
			(options
				(clearance outline)
				(anchor circle)
			)
			(primitives
				(gr_poly
					(pts
						(arc
							(start -0.1778 -0.2794)
							(mid -0.249642 -0.249642)
							(end -0.2794 -0.1778)
						)
						(arc
							(start -0.2794 0.1778)
							(mid -0.249642 0.249642)
							(end -0.1778 0.2794)
						)
						(arc
							(start 0.1778 0.2794)
							(mid 0.249642 0.249642)
							(end 0.2794 0.1778)
						)
						(arc
							(start 0.2794 -0.1778)
							(mid 0.249642 -0.249642)
							(end 0.1778 -0.2794)
						)
					)
					(width 0)
					(fill yes)
				)
			)
		)
	)
	(footprint ""
		(layer "F.Cu")
		(at 149.345396 -131.49453)
		(property "Reference" "R1069"
			(at 0 0 0)
			(layer "F.SilkS")
			(hide yes)
			(effects
				(font
					(size 1.27 1.27)
				)
			)
		)
		(property "Value" "0R5J-5-GP"
			(at 0 -8.9535 0)
			(unlocked yes)
			(layer "F.Fab")
			(hide yes)
			(effects
				(font
					(size 1.27 1.016)
					(thickness 0.1524)
				)
			)
		)
		(property "Device Type" "R805H24"
			(at 0 -10.6299 0)
			(unlocked yes)
			(layer "F.Fab")
			(hide yes)
			(effects
				(font
					(size 1.27 1.016)
					(thickness 0.1524)
				)
			)
		)
		(duplicate_pad_numbers_are_jumpers no)
		(fp_line
			(start -0.889 -1.7018)
			(end -0.889 0.2794)
			(stroke
				(width 0.1524)
				(type default)
			)
			(layer "F.SilkS")
		)
		(fp_line
			(start -0.889 0.0762)
			(end -0.889 1.7018)
			(stroke
				(width 0.1524)
				(type default)
			)
			(layer "F.SilkS")
		)
		(fp_line
			(start -0.889 1.7018)
			(end 0.889 1.7018)
			(stroke
				(width 0.1524)
				(type default)
			)
			(layer "F.SilkS")
		)
		(fp_line
			(start 0.889 -1.7018)
			(end -0.889 -1.7018)
			(stroke
				(width 0.1524)
				(type default)
			)
			(layer "F.SilkS")
		)
		(fp_line
			(start 0.889 -1.7018)
			(end 0.889 -0.381)
			(stroke
				(width 0.1524)
				(type default)
			)
			(layer "F.SilkS")
		)
		(fp_line
			(start 0.889 1.7018)
			(end 0.889 -0.508)
			(stroke
				(width 0.1524)
				(type default)
			)
			(layer "F.SilkS")
		)
		(fp_poly
			(pts
				(xy 0.9652 -1.778) (xy 0.9652 1.778) (xy -0.9652 1.778) (xy -0.9652 -1.778)
			)
			(stroke
				(width 0)
				(type default)
			)
			(fill no)
			(layer "F.CrtYd")
		)
		(fp_rect
			(start -0.9652 1.778)
			(end 0.9652 -1.778)
			(stroke
				(width 0)
				(type default)
			)
			(fill no)
			(layer "F.Fab")
		)
		(pad "1" smd rect
			(at 0 -0.9652)
			(size 1.397 1.143)
			(layers "F.Cu" "F.Mask" "F.Paste")
			(net "MB0_CM_GATE")
		)
		(pad "2" smd rect
			(at 0 0.9652)
			(size 1.397 1.143)
			(layers "F.Cu" "F.Mask" "F.Paste")
			(net "MB0_CM_GATE_R")
		)
	)
	(footprint ""
		(layer "F.Cu")
		(at 181.991 -304.462942 180)
		(property "Reference" "C112"
			(at 0 0 180)
			(layer "F.SilkS")
			(hide yes)
			(effects
				(font
					(size 1.27 1.27)
				)
			)
		)
		(property "Value" "SC1U25V3KX-GP"
			(at 0 -2.8194 180)
			(unlocked yes)
			(layer "F.Fab")
			(hide yes)
			(effects
				(font
					(size 1.016 1.016)
					(thickness 0.1524)
				)
			)
		)
		(property "Device Type" "C603H36"
			(at 0 -4.3434 180)
			(unlocked yes)
			(layer "F.Fab")
			(hide yes)
			(effects
				(font
					(size 1.016 1.016)
					(thickness 0.1524)
				)
			)
		)
		(duplicate_pad_numbers_are_jumpers no)
		(fp_line
			(start 0.508 0)
			(end -0.508 0)
			(stroke
				(width 0.2032)
				(type default)
			)
			(layer "F.SilkS")
		)
		(fp_rect
			(start -0.5842 1.3335)
			(end 0.5842 -1.3335)
			(stroke
				(width 0)
				(type default)
			)
			(fill no)
			(layer "F.CrtYd")
		)
		(fp_rect
			(start -0.5842 1.3335)
			(end 0.5842 -1.3335)
			(stroke
				(width 0)
				(type default)
			)
			(fill no)
			(layer "F.Fab")
		)
		(pad "1" smd custom
			(at 0 -0.762 180)
			(size 0.2159 0.2159)
			(layers "F.Cu" "F.Mask" "F.Paste")
			(net "P12V_HDD5")
			(options
				(clearance outline)
				(anchor circle)
			)
			(primitives
				(gr_poly
					(pts
						(arc
							(start -0.3302 -0.4318)
							(mid -0.402042 -0.402042)
							(end -0.4318 -0.3302)
						)
						(arc
							(start -0.4318 0.3302)
							(mid -0.402042 0.402042)
							(end -0.3302 0.4318)
						)
						(arc
							(start 0.3302 0.4318)
							(mid 0.402042 0.402042)
							(end 0.4318 0.3302)
						)
						(arc
							(start 0.4318 -0.3302)
							(mid 0.402042 -0.402042)
							(end 0.3302 -0.4318)
						)
					)
					(width 0)
					(fill yes)
				)
			)
		)
		(pad "2" smd custom
			(at 0 0.762 180)
			(size 0.2159 0.2159)
			(layers "F.Cu" "F.Mask" "F.Paste")
			(net "GND")
			(options
				(clearance outline)
				(anchor circle)
			)
			(primitives
				(gr_poly
					(pts
						(arc
							(start -0.3302 -0.4318)
							(mid -0.402042 -0.402042)
							(end -0.4318 -0.3302)
						)
						(arc
							(start -0.4318 0.3302)
							(mid -0.402042 0.402042)
							(end -0.3302 0.4318)
						)
						(arc
							(start 0.3302 0.4318)
							(mid 0.402042 0.402042)
							(end 0.4318 0.3302)
						)
						(arc
							(start 0.4318 -0.3302)
							(mid 0.402042 -0.402042)
							(end 0.3302 -0.4318)
						)
					)
					(width 0)
					(fill yes)
				)
			)
		)
	)
	(footprint ""
		(layer "F.Cu")
		(at 430.438052 -42.585894 180)
		(property "Reference" "R899"
			(at 0 0 180)
			(layer "F.SilkS")
			(hide yes)
			(effects
				(font
					(size 1.27 1.27)
				)
			)
		)
		(property "Value" "0R2J-2-GP"
			(at 0.064008 -3.993896 180)
			(unlocked yes)
			(layer "F.Fab")
			(hide yes)
			(effects
				(font
					(size 1.016 1.016)
					(thickness 0.1524)
				)
			)
		)
		(property "Device Type" "R402H16"
			(at 0.064008 -5.517896 180)
			(unlocked yes)
			(layer "F.Fab")
			(hide yes)
			(effects
				(font
					(size 1.016 1.016)
					(thickness 0.1524)
				)
			)
		)
		(duplicate_pad_numbers_are_jumpers no)
		(fp_line
			(start 0.508 -0.9398)
			(end -0.508 -0.9398)
			(stroke
				(width 0.1524)
				(type default)
			)
			(layer "F.SilkS")
		)
		(fp_line
			(start -0.508 -0.9398)
			(end -0.508 0.9398)
			(stroke
				(width 0.1524)
				(type default)
			)
			(layer "F.SilkS")
		)
		(fp_rect
			(start -0.508 0.9398)
			(end 0.508 -0.9398)
			(stroke
				(width 0)
				(type default)
			)
			(fill no)
			(layer "F.CrtYd")
		)
		(fp_rect
			(start -0.508 0.9398)
			(end 0.508 -0.9398)
			(stroke
				(width 0)
				(type default)
			)
			(fill no)
			(layer "F.Fab")
		)
		(pad "1" smd custom
			(at 0 -0.4445 180)
			(size 0.1397 0.1397)
			(layers "F.Cu" "F.Mask" "F.Paste")
			(net "DRIVE_A_33_PWR")
			(options
				(clearance outline)
				(anchor circle)
			)
			(primitives
				(gr_poly
					(pts
						(arc
							(start -0.1778 -0.2794)
							(mid -0.249642 -0.249642)
							(end -0.2794 -0.1778)
						)
						(arc
							(start -0.2794 0.1778)
							(mid -0.249642 0.249642)
							(end -0.1778 0.2794)
						)
						(arc
							(start 0.1778 0.2794)
							(mid 0.249642 0.249642)
							(end 0.2794 0.1778)
						)
						(arc
							(start 0.2794 -0.1778)
							(mid 0.249642 -0.249642)
							(end 0.1778 -0.2794)
						)
					)
					(width 0)
					(fill yes)
				)
			)
		)
		(pad "2" smd custom
			(at 0 0.4445 180)
			(size 0.1397 0.1397)
			(layers "F.Cu" "F.Mask" "F.Paste")
			(net "SW_PWR_R_HDD33")
			(options
				(clearance outline)
				(anchor circle)
			)
			(primitives
				(gr_poly
					(pts
						(arc
							(start -0.1778 -0.2794)
							(mid -0.249642 -0.249642)
							(end -0.2794 -0.1778)
						)
						(arc
							(start -0.2794 0.1778)
							(mid -0.249642 0.249642)
							(end -0.1778 0.2794)
						)
						(arc
							(start 0.1778 0.2794)
							(mid 0.249642 0.249642)
							(end 0.2794 0.1778)
						)
						(arc
							(start 0.2794 -0.1778)
							(mid 0.249642 -0.249642)
							(end 0.1778 -0.2794)
						)
					)
					(width 0)
					(fill yes)
				)
			)
		)
	)
	(footprint ""
		(layer "F.Cu")
		(at 35.543998 -183.747918)
		(property "Reference" "TP62"
			(at 0 0 0)
			(layer "F.SilkS")
			(hide yes)
			(effects
				(font
					(size 1.27 1.27)
				)
			)
		)
		(property "Value" "TPAD32-GP"
			(at -0.0508 -1.6764 0)
			(unlocked yes)
			(layer "F.Fab")
			(hide yes)
			(effects
				(font
					(size 1.016 1.016)
					(thickness 0.1524)
				)
			)
		)
		(property "Device Type" "TPAD32"
			(at -0.0508 -3.2004 0)
			(unlocked yes)
			(layer "F.Fab")
			(hide yes)
			(effects
				(font
					(size 1.016 1.016)
					(thickness 0.1524)
				)
			)
		)
		(duplicate_pad_numbers_are_jumpers no)
		(fp_poly
			(pts
				(arc
					(start 0.4064 0)
					(mid -0.4064 0)
					(end 0.4064 0)
				)
			)
			(stroke
				(width 0)
				(type default)
			)
			(fill no)
			(layer "F.CrtYd")
		)
		(fp_poly
			(pts
				(arc
					(start 0.7112 0)
					(mid -0.7112 0)
					(end 0.7112 0)
				)
			)
			(stroke
				(width 0)
				(type default)
			)
			(fill no)
			(layer "F.Fab")
		)
		(pad "1" smd circle
			(at 0 0)
			(size 0.8128 0.8128)
			(layers "F.Cu" "F.Mask" "F.Paste")
			(net "ACT_HDD_12")
		)
	)
	(footprint ""
		(layer "F.Cu")
		(at 79.924148 -52.085494 90)
		(property "Reference" "R735"
			(at 0 0 90)
			(layer "F.SilkS")
			(hide yes)
			(effects
				(font
					(size 1.27 1.27)
				)
			)
		)
		(property "Value" "4K7R2J-2-GP"
			(at 0.064008 -3.993896 90)
			(unlocked yes)
			(layer "F.Fab")
			(hide yes)
			(effects
				(font
					(size 1.016 1.016)
					(thickness 0.1524)
				)
			)
		)
		(property "Device Type" "R402H16"
			(at 0.064008 -5.517896 90)
			(unlocked yes)
			(layer "F.Fab")
			(hide yes)
			(effects
				(font
					(size 1.016 1.016)
					(thickness 0.1524)
				)
			)
		)
		(duplicate_pad_numbers_are_jumpers no)
		(fp_line
			(start 0.508 -0.9398)
			(end -0.508 -0.9398)
			(stroke
				(width 0.1524)
				(type default)
			)
			(layer "F.SilkS")
		)
		(fp_line
			(start -0.508 -0.9398)
			(end -0.508 0.9398)
			(stroke
				(width 0.1524)
				(type default)
			)
			(layer "F.SilkS")
		)
		(fp_rect
			(start -0.508 0.9398)
			(end 0.508 -0.9398)
			(stroke
				(width 0)
				(type default)
			)
			(fill no)
			(layer "F.CrtYd")
		)
		(fp_rect
			(start -0.508 0.9398)
			(end 0.508 -0.9398)
			(stroke
				(width 0)
				(type default)
			)
			(fill no)
			(layer "F.Fab")
		)
		(pad "1" smd custom
			(at 0 -0.4445 90)
			(size 0.1397 0.1397)
			(layers "F.Cu" "F.Mask" "F.Paste")
			(net "P12V_A")
			(options
				(clearance outline)
				(anchor circle)
			)
			(primitives
				(gr_poly
					(pts
						(arc
							(start -0.1778 -0.2794)
							(mid -0.249642 -0.249642)
							(end -0.2794 -0.1778)
						)
						(arc
							(start -0.2794 0.1778)
							(mid -0.249642 0.249642)
							(end -0.1778 0.2794)
						)
						(arc
							(start 0.1778 0.2794)
							(mid 0.249642 0.249642)
							(end 0.2794 0.1778)
						)
						(arc
							(start 0.2794 -0.1778)
							(mid 0.249642 -0.249642)
							(end 0.1778 -0.2794)
						)
					)
					(width 0)
					(fill yes)
				)
			)
		)
		(pad "2" smd custom
			(at 0 0.4445 90)
			(size 0.1397 0.1397)
			(layers "F.Cu" "F.Mask" "F.Paste")
			(net "SW_HDD_P26")
			(options
				(clearance outline)
				(anchor circle)
			)
			(primitives
				(gr_poly
					(pts
						(arc
							(start -0.1778 -0.2794)
							(mid -0.249642 -0.249642)
							(end -0.2794 -0.1778)
						)
						(arc
							(start -0.2794 0.1778)
							(mid -0.249642 0.249642)
							(end -0.1778 0.2794)
						)
						(arc
							(start 0.1778 0.2794)
							(mid 0.249642 0.249642)
							(end 0.2794 0.1778)
						)
						(arc
							(start 0.2794 -0.1778)
							(mid 0.249642 -0.249642)
							(end 0.1778 -0.2794)
						)
					)
					(width 0)
					(fill yes)
				)
			)
		)
	)
	(footprint ""
		(layer "F.Cu")
		(at 430.438052 -272.585942 180)
		(property "Reference" "R348"
			(at 0 0 180)
			(layer "F.SilkS")
			(hide yes)
			(effects
				(font
					(size 1.27 1.27)
				)
			)
		)
		(property "Value" "0R2J-2-GP"
			(at 0.064008 -3.993896 180)
			(unlocked yes)
			(layer "F.Fab")
			(hide yes)
			(effects
				(font
					(size 1.016 1.016)
					(thickness 0.1524)
				)
			)
		)
		(property "Device Type" "R402H16"
			(at 0.064008 -5.517896 180)
			(unlocked yes)
			(layer "F.Fab")
			(hide yes)
			(effects
				(font
					(size 1.016 1.016)
					(thickness 0.1524)
				)
			)
		)
		(duplicate_pad_numbers_are_jumpers no)
		(fp_line
			(start 0.508 -0.9398)
			(end -0.508 -0.9398)
			(stroke
				(width 0.1524)
				(type default)
			)
			(layer "F.SilkS")
		)
		(fp_line
			(start -0.508 -0.9398)
			(end -0.508 0.9398)
			(stroke
				(width 0.1524)
				(type default)
			)
			(layer "F.SilkS")
		)
		(fp_rect
			(start -0.508 0.9398)
			(end 0.508 -0.9398)
			(stroke
				(width 0)
				(type default)
			)
			(fill no)
			(layer "F.CrtYd")
		)
		(fp_rect
			(start -0.508 0.9398)
			(end 0.508 -0.9398)
			(stroke
				(width 0)
				(type default)
			)
			(fill no)
			(layer "F.Fab")
		)
		(pad "1" smd custom
			(at 0 -0.4445 180)
			(size 0.1397 0.1397)
			(layers "F.Cu" "F.Mask" "F.Paste")
			(net "DRIVE_A_9_PWR")
			(options
				(clearance outline)
				(anchor circle)
			)
			(primitives
				(gr_poly
					(pts
						(arc
							(start -0.1778 -0.2794)
							(mid -0.249642 -0.249642)
							(end -0.2794 -0.1778)
						)
						(arc
							(start -0.2794 0.1778)
							(mid -0.249642 0.249642)
							(end -0.1778 0.2794)
						)
						(arc
							(start 0.1778 0.2794)
							(mid 0.249642 0.249642)
							(end 0.2794 0.1778)
						)
						(arc
							(start 0.2794 -0.1778)
							(mid 0.249642 -0.249642)
							(end 0.1778 -0.2794)
						)
					)
					(width 0)
					(fill yes)
				)
			)
		)
		(pad "2" smd custom
			(at 0 0.4445 180)
			(size 0.1397 0.1397)
			(layers "F.Cu" "F.Mask" "F.Paste")
			(net "SW_PWR_R_HDD9")
			(options
				(clearance outline)
				(anchor circle)
			)
			(primitives
				(gr_poly
					(pts
						(arc
							(start -0.1778 -0.2794)
							(mid -0.249642 -0.249642)
							(end -0.2794 -0.1778)
						)
						(arc
							(start -0.2794 0.1778)
							(mid -0.249642 0.249642)
							(end -0.1778 0.2794)
						)
						(arc
							(start 0.1778 0.2794)
							(mid 0.249642 0.249642)
							(end 0.2794 0.1778)
						)
						(arc
							(start 0.2794 -0.1778)
							(mid 0.249642 -0.249642)
							(end 0.1778 -0.2794)
						)
					)
					(width 0)
					(fill yes)
				)
			)
		)
	)
	(footprint ""
		(layer "F.Cu")
		(at 180.7464 -161.014918 -90)
		(property "Reference" "R529"
			(at 0 0 270)
			(layer "F.SilkS")
			(hide yes)
			(effects
				(font
					(size 1.27 1.27)
				)
			)
		)
		(property "Value" "1KR2F-3-GP"
			(at 0.064008 -3.993896 270)
			(unlocked yes)
			(layer "F.Fab")
			(hide yes)
			(effects
				(font
					(size 1.016 1.016)
					(thickness 0.1524)
				)
			)
		)
		(property "Device Type" "R402H16"
			(at 0.064008 -5.517896 270)
			(unlocked yes)
			(layer "F.Fab")
			(hide yes)
			(effects
				(font
					(size 1.016 1.016)
					(thickness 0.1524)
				)
			)
		)
		(duplicate_pad_numbers_are_jumpers no)
		(fp_line
			(start -0.508 -0.9398)
			(end -0.508 0.9398)
			(stroke
				(width 0.1524)
				(type default)
			)
			(layer "F.SilkS")
		)
		(fp_line
			(start 0.508 -0.9398)
			(end -0.508 -0.9398)
			(stroke
				(width 0.1524)
				(type default)
			)
			(layer "F.SilkS")
		)
		(fp_rect
			(start -0.508 0.9398)
			(end 0.508 -0.9398)
			(stroke
				(width 0)
				(type default)
			)
			(fill no)
			(layer "F.CrtYd")
		)
		(fp_rect
			(start -0.508 0.9398)
			(end 0.508 -0.9398)
			(stroke
				(width 0)
				(type default)
			)
			(fill no)
			(layer "F.Fab")
		)
		(pad "1" smd custom
			(at 0 -0.4445 270)
			(size 0.1397 0.1397)
			(layers "F.Cu" "F.Mask" "F.Paste")
			(net "P3V3_STBY_A")
			(options
				(clearance outline)
				(anchor circle)
			)
			(primitives
				(gr_poly
					(pts
						(arc
							(start -0.1778 -0.2794)
							(mid -0.249642 -0.249642)
							(end -0.2794 -0.1778)
						)
						(arc
							(start -0.2794 0.1778)
							(mid -0.249642 0.249642)
							(end -0.1778 0.2794)
						)
						(arc
							(start 0.1778 0.2794)
							(mid 0.249642 0.249642)
							(end 0.2794 0.1778)
						)
						(arc
							(start 0.2794 -0.1778)
							(mid 0.249642 -0.249642)
							(end 0.1778 -0.2794)
						)
					)
					(width 0)
					(fill yes)
				)
			)
		)
		(pad "2" smd custom
			(at 0 0.4445 270)
			(size 0.1397 0.1397)
			(layers "F.Cu" "F.Mask" "F.Paste")
			(net "SW_PWR_R_HDD17")
			(options
				(clearance outline)
				(anchor circle)
			)
			(primitives
				(gr_poly
					(pts
						(arc
							(start -0.1778 -0.2794)
							(mid -0.249642 -0.249642)
							(end -0.2794 -0.1778)
						)
						(arc
							(start -0.2794 0.1778)
							(mid -0.249642 0.249642)
							(end -0.1778 0.2794)
						)
						(arc
							(start 0.1778 0.2794)
							(mid 0.249642 0.249642)
							(end 0.2794 0.1778)
						)
						(arc
							(start 0.2794 -0.1778)
							(mid 0.249642 -0.249642)
							(end 0.1778 -0.2794)
						)
					)
					(width 0)
					(fill yes)
				)
			)
		)
	)
)
